# S9S_MB_2U (Grand Teton) — schematic netlist excerpt (pin names and nets, part order shuffled) for the footprints in the layout excerpt that follows; sources: Cadence DE-HDL packaged netlist, KiCad conversion of 03242023_DA0F0TMBIJ0_F0T_Motherboard_J_brd_V01_OCP.brd

R1305  Q_RES  10K 1% EMPTY  pkg 0402LF  page 208 : A = P3V3_AUX ; B = FM_PLD_CLKS_DEV_EN
R4633  Q_RES  0 5% CHIP  pkg 0402LF  page 248 : A = JTAG_BMC_SW_TCK_R ; B = JTAG_BMC_SW_TCK

(kicad_pcb
	(version 20260206)
	(generator "pcbnew")
	(generator_version "10.0")
	(general
		(thickness 1.6)
		(legacy_teardrops no)
	)
	(paper "A4")
	(title_block
		(title "03242023_DA0F0TMBIJ0_F0T_Motherboard_J_brd_V01_OCP.brd")
		(comment 1 "Grand Teton / footprints 994-995 of 6105")
	)
	(layers
		(0 "F.Cu" signal "TOP")
		(4 "In1.Cu" signal "GND")
		(6 "In2.Cu" signal "IN1")
		(8 "In3.Cu" signal "GND1")
		(10 "In4.Cu" signal "IN2")
		(12 "In5.Cu" signal "GND2")
		(14 "In6.Cu" signal "IN3")
		(16 "In7.Cu" signal "GND3")
		(18 "In8.Cu" signal "VCC")
		(20 "In9.Cu" signal "VCC1")
		(22 "In10.Cu" signal "GND4")
		(24 "In11.Cu" signal "IN4")
		(26 "In12.Cu" signal "GND5")
		(28 "In13.Cu" signal "IN5")
		(30 "In14.Cu" signal "GND6")
		(32 "In15.Cu" signal "IN6")
		(34 "In16.Cu" signal "GND7")
		(2 "B.Cu" signal "BOTTOM")
		(9 "F.Adhes" user "F.Adhesive")
		(11 "B.Adhes" user "B.Adhesive")
		(13 "F.Paste" user "Package Geometry/Pastemask Top")
		(15 "B.Paste" user "Package Geometry/Pastemask Bottom")
		(5 "F.SilkS" user "Ref Des/Silkscreen Top")
		(7 "B.SilkS" user "Ref Des/Silkscreen Bottom")
		(1 "F.Mask" user "Board Geometry/Soldermask Top")
		(3 "B.Mask" user "Board Geometry/Soldermask Bottom")
		(17 "Dwgs.User" user "User.Drawings")
		(19 "Cmts.User" user "User.Comments")
		(21 "Eco1.User" user "User.Eco1")
		(23 "Eco2.User" user "User.Eco2")
		(25 "Edge.Cuts" user "Board Geometry/Outline")
		(27 "Margin" user)
		(31 "F.CrtYd" user "Package Geometry/Place Bound Top")
		(29 "B.CrtYd" user "Package Geometry/Place Bound Bottom")
		(35 "F.Fab" user "Ref Des/Assembly Top")
		(33 "B.Fab" user "Ref Des/Assembly Bottom")
	)
	(footprint ""
		(layer "F.Cu")
		(at 267.38707 -92.63253 -90)
		(property "Reference" "R1305"
			(at 0 0 270)
			(layer "F.SilkS")
			(hide yes)
			(effects
				(font
					(size 1.27 1.27)
				)
			)
		)
		(property "Value" ""
			(at 0 0 270)
			(layer "F.Fab")
			(effects
				(font
					(size 1.27 1.27)
				)
			)
		)
		(duplicate_pad_numbers_are_jumpers no)
		(fp_line
			(start -0.7874 0.4064)
			(end -0.7874 -0.4064)
			(stroke
				(width 0.1524)
				(type default)
			)
			(layer "F.SilkS")
		)
		(fp_line
			(start 0.7874 0.4064)
			(end -0.7874 0.4064)
			(stroke
				(width 0.1524)
				(type default)
			)
			(layer "F.SilkS")
		)
		(fp_line
			(start -0.7874 -0.4064)
			(end 0.7874 -0.4064)
			(stroke
				(width 0.1524)
				(type default)
			)
			(layer "F.SilkS")
		)
		(fp_line
			(start 0.7874 -0.4064)
			(end 0.7874 0.4064)
			(stroke
				(width 0.1524)
				(type default)
			)
			(layer "F.SilkS")
		)
		(fp_line
			(start -0.67945 0.3048)
			(end -0.67945 -0.305054)
			(stroke
				(width 0.1)
				(type default)
			)
			(layer "F.Fab")
		)
		(fp_line
			(start -0.12065 0.3048)
			(end -0.67945 0.3048)
			(stroke
				(width 0.1)
				(type default)
			)
			(layer "F.Fab")
		)
		(fp_line
			(start 0.120396 0.3048)
			(end 0.120396 0.2794)
			(stroke
				(width 0.1)
				(type default)
			)
			(layer "F.Fab")
		)
		(fp_line
			(start 0.67945 0.3048)
			(end 0.120396 0.3048)
			(stroke
				(width 0.1)
				(type default)
			)
			(layer "F.Fab")
		)
		(fp_line
			(start -0.12065 0.2794)
			(end -0.12065 0.3048)
			(stroke
				(width 0.1)
				(type default)
			)
			(layer "F.Fab")
		)
		(fp_line
			(start 0.120396 0.2794)
			(end -0.12065 0.2794)
			(stroke
				(width 0.1)
				(type default)
			)
			(layer "F.Fab")
		)
		(fp_line
			(start -0.12065 -0.2794)
			(end 0.12065 -0.2794)
			(stroke
				(width 0.1)
				(type default)
			)
			(layer "F.Fab")
		)
		(fp_line
			(start 0.12065 -0.2794)
			(end 0.12065 -0.3048)
			(stroke
				(width 0.1)
				(type default)
			)
			(layer "F.Fab")
		)
		(fp_line
			(start 0.12065 -0.3048)
			(end 0.67945 -0.3048)
			(stroke
				(width 0.1)
				(type default)
			)
			(layer "F.Fab")
		)
		(fp_line
			(start 0.67945 -0.3048)
			(end 0.67945 0.3048)
			(stroke
				(width 0.1)
				(type default)
			)
			(layer "F.Fab")
		)
		(fp_line
			(start -0.67945 -0.305054)
			(end -0.12065 -0.305054)
			(stroke
				(width 0.1)
				(type default)
			)
			(layer "F.Fab")
		)
		(fp_line
			(start -0.12065 -0.305054)
			(end -0.12065 -0.2794)
			(stroke
				(width 0.1)
				(type default)
			)
			(layer "F.Fab")
		)
		(pad "1" smd circle
			(at -0.40005 0 270)
			(size 0 0)
			(layers "F.Cu" "F.Mask" "F.Paste")
			(net "P3V3_AUX")
		)
		(pad "2" smd circle
			(at 0.40005 0 270)
			(size 0 0)
			(layers "F.Cu" "F.Mask" "F.Paste")
			(net "FM_PLD_CLKS_DEV_EN")
		)
	)
	(footprint ""
		(layer "F.Cu")
		(at 115.951 -56.479948 180)
		(property "Reference" "R4633"
			(at 0 0 180)
			(layer "F.SilkS")
			(hide yes)
			(effects
				(font
					(size 1.27 1.27)
				)
			)
		)
		(property "Value" ""
			(at 0 0 180)
			(layer "F.Fab")
			(effects
				(font
					(size 1.27 1.27)
				)
			)
		)
		(duplicate_pad_numbers_are_jumpers no)
		(fp_line
			(start 0.7874 0.4064)
			(end -0.7874 0.4064)
			(stroke
				(width 0.1524)
				(type default)
			)
			(layer "F.SilkS")
		)
		(fp_line
			(start 0.7874 -0.4064)
			(end 0.7874 0.4064)
			(stroke
				(width 0.1524)
				(type default)
			)
			(layer "F.SilkS")
		)
		(fp_line
			(start -0.7874 0.4064)
			(end -0.7874 -0.4064)
			(stroke
				(width 0.1524)
				(type default)
			)
			(layer "F.SilkS")
		)
		(fp_line
			(start -0.7874 -0.4064)
			(end 0.7874 -0.4064)
			(stroke
				(width 0.1524)
				(type default)
			)
			(layer "F.SilkS")
		)
		(fp_line
			(start 0.67945 0.3048)
			(end 0.120396 0.3048)
			(stroke
				(width 0.1)
				(type default)
			)
			(layer "F.Fab")
		)
		(fp_line
			(start 0.67945 -0.3048)
			(end 0.67945 0.3048)
			(stroke
				(width 0.1)
				(type default)
			)
			(layer "F.Fab")
		)
		(fp_line
			(start 0.12065 -0.2794)
			(end 0.12065 -0.3048)
			(stroke
				(width 0.1)
				(type default)
			)
			(layer "F.Fab")
		)
		(fp_line
			(start 0.12065 -0.3048)
			(end 0.67945 -0.3048)
			(stroke
				(width 0.1)
				(type default)
			)
			(layer "F.Fab")
		)
		(fp_line
			(start 0.120396 0.3048)
			(end 0.120396 0.2794)
			(stroke
				(width 0.1)
				(type default)
			)
			(layer "F.Fab")
		)
		(fp_line
			(start 0.120396 0.2794)
			(end -0.12065 0.2794)
			(stroke
				(width 0.1)
				(type default)
			)
			(layer "F.Fab")
		)
		(fp_line
			(start -0.12065 0.3048)
			(end -0.67945 0.3048)
			(stroke
				(width 0.1)
				(type default)
			)
			(layer "F.Fab")
		)
		(fp_line
			(start -0.12065 0.2794)
			(end -0.12065 0.3048)
			(stroke
				(width 0.1)
				(type default)
			)
			(layer "F.Fab")
		)
		(fp_line
			(start -0.12065 -0.2794)
			(end 0.12065 -0.2794)
			(stroke
				(width 0.1)
				(type default)
			)
			(layer "F.Fab")
		)
		(fp_line
			(start -0.12065 -0.305054)
			(end -0.12065 -0.2794)
			(stroke
				(width 0.1)
				(type default)
			)
			(layer "F.Fab")
		)
		(fp_line
			(start -0.67945 0.3048)
			(end -0.67945 -0.305054)
			(stroke
				(width 0.1)
				(type default)
			)
			(layer "F.Fab")
		)
		(fp_line
			(start -0.67945 -0.305054)
			(end -0.12065 -0.305054)
			(stroke
				(width 0.1)
				(type default)
			)
			(layer "F.Fab")
		)
		(pad "1" smd circle
			(at -0.40005 0 180)
			(size 0 0)
			(layers "F.Cu" "F.Mask" "F.Paste")
			(net "JTAG_BMC_SW_TCK_R")
		)
		(pad "2" smd circle
			(at 0.40005 0 180)
			(size 0 0)
			(layers "F.Cu" "F.Mask" "F.Paste")
			(net "JTAG_BMC_SW_TCK")
		)
	)
)
